FILE_TYPE = MULTI_PHYS_TABLE;

PART 'SW20S_DHNF10FQTR'

{========================================================================================}
:VALUE                  | PART_TYPE | MATERIAL | PART_NUMBER    = STANDARD | LIFECYCLE     | PART_NUMBER   | JEDEC_TYPE          | DESCRIPTION                      | MANUFTR | MANUF_PN         | RD_CMPLS_LVL | CMPLS_LVL | CLASS | DIP_SMD | FROM_PJ    | DATA                    | FP_ECN              | EE_CHECK_LIST | PSL | PREFERENCE | CREATOR | CREATEDAY  | STATUS | ESD_CDM | ESD_HBM | ESD_MM | MSD  | PIN_LENGTH_LONG_PIN | PIN_LENGTH_SHORT_PIN ;
{========================================================================================}
 'SW20S_DHNF-10F-Q-T/R' | 'SMLF'    | 'MECH'   | 'DHD00010F01'(!) = ''       | ''               | 'DHD00010F01' |'SW20S_DHNF10FTVTR'| 'SWITCH SMD DIP(DHNF-10F-Q-T/R)' | 'DIP'   | 'DHNF-10F-Q-T/R' | 'EP(V1)'     | ''        | 'IO'  | ''      | 'F0C-IVES' | 'DIP_DHNF-10F-Q-TR.pdf' | 'DHNF-10F-Q-TR.msg' | ''            | ''  | ''         | ''      | '20210119' | ''     | '0'     | '0'     | '0'    | 'NA' | '0 MILS'            | '0 MILS'            
 'SW20S_DHNF-10F-Q-T/R' | 'SMLF'    | 'EMPTY'  | 'DHD00010F01'(!) = ''       | ''               | 'DHD00010F01' |'SW20S_DHNF10FTVTR'| 'SWITCH SMD DIP(DHNF-10F-Q-T/R)' | 'DIP'   | 'DHNF-10F-Q-T/R' | 'EP(V1)'     | ''        | 'IO'  | ''      | 'F0C-IVES' | 'DIP_DHNF-10F-Q-TR.pdf' | 'DHNF-10F-Q-TR.msg' | ''            | ''  | ''         | ''      | '20210119' | ''     | '0'     | '0'     | '0'    | 'NA' | '0 MILS'            | '0 MILS'            

END_PART

END.

